FILE_TYPE = CONNECTIVITY;
{Allegro Design Entry HDL 16.6-p007 (v16-6-112F) 10/10/2012}
"PAGE_NUMBER" = 47;
0"NC";
1"M_C_DQS_DP<17:0>";
2"M_C_DQS_DN<17:0>";
3"M_C_MA<17:0>";
4"M_C_DQ<63:0>";
5"M_C_CLK_DN<3:0>";
6"M_C_CLK_DP<3:0>";
7"M_C_CS_N<7:0>";
8"M_C_ECC<7:0>";
9"M_C_CKE<3:0>";
10"M_C_BG<1:0>";
11"M_C_BA<1:0>";
12"M_C_ODT<3:0>";
13"PVTT_ABC\g";
14"PVDDQ_ABC\g";
15"GND\g";
16"GND\g";
17"GND\g";
18"PVPP_ABC\g";
19"PVPP_ABC\g";
20"P12V_NVDIMM_ABC\g";
21"GND\g";
22"M_C_VREF";
23"TP_CH_C_DIMM_C0_RFU_1";
24"TP_CH_C_DIMM_C0_RFU_0";
25"TP_CH_C_DIMM_C0_RFU_2";
26"M_C_ALERT_N";
27"M_C_ACT_N";
28"SMB_DDR_ABC_VPP_SCL";
29"SMB_DDR_ABC_VPP_SDA";
30"FM_ADR_COMPLETE_ABC_N";
31"FM_DIMM_EVENT_COD_N";
32"M_ABC_RST_N";
33"M_C_PAR";
34"M_C_C<2>";
35"M_C_CS_N<0>";
36"M_C_CKE<0>";
37"M_C_ODT<1>";
38"M_C_ODT<0>";
39"M_C_ECC<6>";
40"M_C_MA<2>";
41"M_C_BA<0>";
42"M_C_BG<1>";
43"M_C_BG<0>";
44"M_C_CKE<1>";
45"M_C_ECC<1>";
46"M_C_ECC<0>";
47"M_C_ECC<3>";
48"M_C_ECC<2>";
49"M_C_ECC<5>";
50"M_C_ECC<4>";
51"M_C_ECC<7>";
52"M_C_MA<5>";
53"M_C_MA<4>";
54"M_C_MA<3>";
55"M_C_MA<1>";
56"M_C_MA<0>";
57"M_C_CS_N<1>";
58"M_C_CS_N<2>";
59"M_C_CS_N<3>";
60"M_C_BA<1>";
61"M_C_CLK_DP<1>";
62"M_C_CLK_DN<0>";
63"M_C_CLK_DP<0>";
64"M_C_CLK_DN<1>";
65"M_C_DQ<1>";
66"M_C_DQ<4>";
67"M_C_DQ<5>";
68"M_C_DQ<2>";
69"M_C_DQ<3>";
70"M_C_DQ<0>";
71"M_C_DQ<7>";
72"M_C_DQ<6>";
73"M_C_DQ<9>";
74"M_C_DQ<8>";
75"M_C_DQ<11>";
76"M_C_DQ<16>";
77"M_C_DQ<14>";
78"M_C_DQ<10>";
79"M_C_DQ<13>";
80"M_C_DQ<12>";
81"M_C_DQ<15>";
82"M_C_DQ<17>";
83"M_C_DQ<19>";
84"M_C_DQ<18>";
85"M_C_DQ<21>";
86"M_C_DQ<20>";
87"M_C_DQ<27>";
88"M_C_DQ<26>";
89"M_C_DQ<23>";
90"M_C_DQ<22>";
91"M_C_DQ<25>";
92"M_C_DQ<24>";
93"M_C_DQ<31>";
94"M_C_DQ<30>";
95"M_C_DQ<29>";
96"M_C_DQ<28>";
97"M_C_DQ<39>";
98"M_C_DQ<37>";
99"M_C_DQ<34>";
100"M_C_DQ<33>";
101"M_C_DQ<32>";
102"M_C_DQ<35>";
103"M_C_DQ<36>";
104"M_C_DQ<38>";
105"M_C_DQ<41>";
106"M_C_DQ<40>";
107"M_C_DQ<46>";
108"M_C_DQ<49>";
109"M_C_DQ<48>";
110"M_C_DQ<51>";
111"M_C_DQ<50>";
112"M_C_DQ<43>";
113"M_C_DQ<42>";
114"M_C_DQ<45>";
115"M_C_DQ<44>";
116"M_C_DQ<47>";
117"M_C_MA<16>";
118"M_C_MA<15>";
119"M_C_MA<14>";
120"M_C_MA<11>";
121"M_C_MA<10>";
122"M_C_MA<9>";
123"M_C_MA<8>";
124"M_C_MA<7>";
125"M_C_MA<6>";
126"M_C_MA<17>";
127"M_C_MA<13>";
128"M_C_MA<12>";
129"M_C_DQ<63>";
130"M_C_DQ<60>";
131"M_C_DQ<53>";
132"M_C_DQ<52>";
133"M_C_DQ<55>";
134"M_C_DQ<59>";
135"M_C_DQ<56>";
136"M_C_DQ<54>";
137"M_C_DQ<57>";
138"M_C_DQ<58>";
139"M_C_DQ<61>";
140"M_C_DQ<62>";
141"M_C_DQS_DN<6>";
142"M_C_DQS_DP<5>";
143"M_C_DQS_DN<5>";
144"M_C_DQS_DP<4>";
145"M_C_DQS_DN<4>";
146"M_C_DQS_DP<3>";
147"M_C_DQS_DN<3>";
148"M_C_DQS_DP<2>";
149"M_C_DQS_DN<2>";
150"M_C_DQS_DP<1>";
151"M_C_DQS_DN<1>";
152"M_C_DQS_DP<0>";
153"M_C_DQS_DN<0>";
154"M_C_DQS_DP<9>";
155"M_C_DQS_DN<9>";
156"M_C_DQS_DP<8>";
157"M_C_DQS_DN<8>";
158"M_C_DQS_DP<7>";
159"M_C_DQS_DN<7>";
160"M_C_DQS_DP<6>";
161"M_C_DQS_DP<16>";
162"M_C_DQS_DN<16>";
163"M_C_DQS_DP<15>";
164"M_C_DQS_DN<15>";
165"M_C_DQS_DP<14>";
166"M_C_DQS_DN<14>";
167"M_C_DQS_DP<13>";
168"M_C_DQS_DN<13>";
169"M_C_DQS_DP<12>";
170"M_C_DQS_DN<12>";
171"M_C_DQS_DP<11>";
172"M_C_DQS_DN<11>";
173"M_C_DQS_DP<10>";
174"M_C_DQS_DN<10>";
175"M_C_DQS_DP<17>";
176"M_C_DQS_DN<17>";
%"TAP"
"6","(700,4900)","2","mstr_standard","I10";
;
HDL_TAP"TRUE"
BODY_TYPE"PLUMBING"
CDS_LIB"mstr_standard";
"B \NAC \NWC"1;
"S \NAC"
BN"14"165;
%"TAP"
"6","(-1700,1900)","2","mstr_standard","I100";
;
HDL_TAP"TRUE"
BODY_TYPE"PLUMBING"
CDS_LIB"mstr_standard";
"B \NAC \NWC"4;
"S \NAC"
BN"9"73;
%"TAP"
"6","(-1700,2000)","2","mstr_standard","I101";
;
HDL_TAP"TRUE"
BODY_TYPE"PLUMBING"
CDS_LIB"mstr_standard";
"B \NAC \NWC"4;
"S \NAC"
BN"11"75;
%"TAP"
"6","(-1700,1950)","2","mstr_standard","I102";
;
HDL_TAP"TRUE"
BODY_TYPE"PLUMBING"
CDS_LIB"mstr_standard";
"B \NAC \NWC"4;
"S \NAC"
BN"8"74;
%"TAP"
"6","(-1700,1750)","2","mstr_standard","I103";
;
HDL_TAP"TRUE"
BODY_TYPE"PLUMBING"
CDS_LIB"mstr_standard";
"B \NAC \NWC"4;
"S \NAC"
BN"4"66;
%"TAP"
"6","(-1700,1800)","2","mstr_standard","I104";
;
HDL_TAP"TRUE"
BODY_TYPE"PLUMBING"
CDS_LIB"mstr_standard";
"B \NAC \NWC"4;
"S \NAC"
BN"7"71;
%"TAP"
"6","(-1700,1850)","2","mstr_standard","I105";
;
HDL_TAP"TRUE"
BODY_TYPE"PLUMBING"
CDS_LIB"mstr_standard";
"B \NAC \NWC"4;
"S \NAC"
BN"6"72;
%"TAP"
"6","(-1700,1700)","2","mstr_standard","I106";
;
HDL_TAP"TRUE"
BODY_TYPE"PLUMBING"
CDS_LIB"mstr_standard";
"B \NAC \NWC"4;
"S \NAC"
BN"5"67;
%"TAP"
"6","(-1700,1650)","2","mstr_standard","I107";
;
HDL_TAP"TRUE"
BODY_TYPE"PLUMBING"
CDS_LIB"mstr_standard";
"B \NAC \NWC"4;
"S \NAC"
BN"2"68;
%"TAP"
"6","(-1700,1550)","2","mstr_standard","I108";
;
HDL_TAP"TRUE"
BODY_TYPE"PLUMBING"
CDS_LIB"mstr_standard";
"B \NAC \NWC"4;
"S \NAC"
BN"0"70;
%"TAP"
"6","(-1700,1600)","2","mstr_standard","I109";
;
HDL_TAP"TRUE"
BODY_TYPE"PLUMBING"
CDS_LIB"mstr_standard";
"B \NAC \NWC"4;
"S \NAC"
BN"3"69;
%"TAP"
"6","(-1700,1500)","2","mstr_standard","I110";
;
HDL_TAP"TRUE"
BODY_TYPE"PLUMBING"
CDS_LIB"mstr_standard";
"B \NAC \NWC"4;
"S \NAC"
BN"1"65;
%"SCONN288_H44441004"
"1","(-2450,3000)","0","mstr_sconn","I111";
;
CDS_SEC"1"
ROOM"DDR4_CH_C"
CDS_LOCATION"J4G3"
SEC"1"
SEC_TYPE"PIP"
CDS_LIB"mstr_sconn"
BOM_COST"MEM"
PACK_TYPE"PIP"
MATERIAL"SCONN"
PART_NUMBER"H44441-004"
LOCATION"J4G3";
"DQ<63>"
$PN"280"140;
"DQ<62>"
$PN"135"129;
"DQ<61>"
$PN"273"130;
"DQ<5>"
$PN"148"66;
"DQ<4>"
$PN"3"67;
"DQ<3>"
$PN"157"68;
"DQ<2>"
$PN"12"69;
"DQ<47>"
$PN"258"107;
"DQ<48>"
$PN"119"108;
"DQ<49>"
$PN"264"109;
"DQ<50>"
$PN"126"110;
"DQ<51>"
$PN"271"111;
"DQ<52>"
$PN"117"131;
"DQ<53>"
$PN"262"132;
"DQ<54>"
$PN"124"133;
"DQ<58>"
$PN"137"134;
"DQ<57>"
$PN"275"135;
"SAVE_N_NC"
$PN"230"30;
"RFU<1>"
$PN"227"23;
"RFU<0>"
$PN"205"24;
"DQ<17>"
$PN"172"76;
"DQ<15>"
$PN"166"77;
"DQ<26>"
$PN"45"87;
"DQ<27>"
$PN"190"88;
"S0_N"
$PN"84"35;
"CKE<0>"
$PN"60"36;
"ODT<1>"
$PN"91"37;
"ODT<0>"
$PN"87"38;
"CB<7>"
$PN"199"39;
"A16_RAS_N"
$PN"82"117;
"A15_CAS_N"
$PN"86"118;
"A14_WE_N"
$PN"228"119;
"A11"
$PN"210"120;
"A10"
$PN"225"121;
"DQ<38>"
$PN"102"97;
"DQ<36>"
$PN"95"98;
"DQ<35>"
$PN"249"99;
"A2"
$PN"216"40;
"ALERT_N"
$PN"208"26;
"ACT_N"
$PN"62"27;
"DQ<0>"
$PN"5"65;
"DQ<1>"
$PN"150"70;
"SA<1>"
$PN"140"16;
"SA<2>"
$PN"238"19;
"VDDSPD"
$PN"284"19;
"SA<0>"
$PN"139"16;
"BA<0>"
$PN"81"41;
"BG<1>"
$PN"207"42;
"BG<0>"
$PN"63"43;
"CK1P"
$PN"218"61;
"VREFCA"
$PN"146"22;
"SDA"
$PN"285"29;
"SCL"
$PN"141"28;
"RFU<2>"
$PN"144"25;
"RESET_N"
$PN"58"32;
"PAR"
$PN"222"33;
"EVENT_N"
$PN"78"31;
"DQ<6>"
$PN"10"71;
"DQ<7>"
$PN"155"72;
"DQ<8>"
$PN"16"73;
"DQ<9>"
$PN"161"74;
"DQ<10>"
$PN"23"75;
"DQ<11>"
$PN"168"78;
"DQ<12>"
$PN"14"79;
"DQ<13>"
$PN"159"80;
"DQ<14>"
$PN"21"81;
"DQ<16>"
$PN"27"82;
"DQ<18>"
$PN"34"83;
"DQ<19>"
$PN"179"84;
"DQ<20>"
$PN"25"85;
"DQ<21>"
$PN"170"86;
"DQ<22>"
$PN"32"89;
"DQ<23>"
$PN"177"90;
"DQ<24>"
$PN"38"91;
"DQ<25>"
$PN"183"92;
"DQ<30>"
$PN"43"93;
"DQ<31>"
$PN"188"94;
"DQ<32>"
$PN"97"100;
"DQ<33>"
$PN"242"101;
"DQ<34>"
$PN"104"102;
"DQ<37>"
$PN"240"103;
"DQ<39>"
$PN"247"104;
"DQ<40>"
$PN"108"105;
"DQ<41>"
$PN"253"106;
"DQ<42>"
$PN"115"112;
"DQ<43>"
$PN"260"113;
"DQ<44>"
$PN"106"114;
"DQ<45>"
$PN"251"115;
"DQ<46>"
$PN"113"116;
"DQ<55>"
$PN"269"136;
"DQ<56>"
$PN"130"137;
"DQ<59>"
$PN"282"138;
"DQ<60>"
$PN"128"139;
"CKE<1>"
$PN"203"44;
"CK0N"
$PN"75"62;
"CB<0>"
$PN"49"45;
"CB<1>"
$PN"194"46;
"CB<2>"
$PN"56"47;
"CB<3>"
$PN"201"48;
"CB<4>"
$PN"47"49;
"CB<5>"
$PN"192"50;
"CB<6>"
$PN"54"51;
"A9"
$PN"66"122;
"A8"
$PN"68"123;
"A7"
$PN"211"124;
"A6"
$PN"69"125;
"A5"
$PN"213"52;
"A4"
$PN"214"53;
"A3"
$PN"71"54;
"A17"
$PN"234"126;
"A13"
$PN"232"127;
"A12"
$PN"65"128;
"A1"
$PN"72"55;
"A0"
$PN"79"56;
"C<2>"
$PN"235"34;
"DQ<28>"
$PN"36"95;
"DQ<29>"
$PN"181"96;
"S1_N"
$PN"89"57;
"S2_N_C<0>"
$PN"93"58;
"S3_N_C<1>"
$PN"237"59;
"CK0P"
$PN"74"63;
"CK1N"
$PN"219"64;
"BA<1>"
$PN"224"60;
%"TAP"
"6","(-3200,4650)","0","mstr_standard","I112";
;
HDL_TAP"TRUE"
BODY_TYPE"PLUMBING"
CDS_LIB"mstr_standard";
"B \NAC \NWC"3;
"S \NAC"
BN"17"126;
%"TAP"
"6","(-3200,4600)","0","mstr_standard","I113";
;
HDL_TAP"TRUE"
BODY_TYPE"PLUMBING"
CDS_LIB"mstr_standard";
"B \NAC \NWC"3;
"S \NAC"
BN"16"117;
%"TAP"
"6","(-3200,4550)","0","mstr_standard","I114";
;
HDL_TAP"TRUE"
BODY_TYPE"PLUMBING"
CDS_LIB"mstr_standard";
"B \NAC \NWC"3;
"S \NAC"
BN"15"118;
%"TAP"
"6","(-3200,4500)","0","mstr_standard","I115";
;
HDL_TAP"TRUE"
BODY_TYPE"PLUMBING"
CDS_LIB"mstr_standard";
"B \NAC \NWC"3;
"S \NAC"
BN"14"119;
%"TAP"
"6","(-3200,4450)","0","mstr_standard","I116";
;
HDL_TAP"TRUE"
BODY_TYPE"PLUMBING"
CDS_LIB"mstr_standard";
"B \NAC \NWC"3;
"S \NAC"
BN"13"127;
%"TAP"
"6","(-3200,4400)","0","mstr_standard","I117";
;
HDL_TAP"TRUE"
BODY_TYPE"PLUMBING"
CDS_LIB"mstr_standard";
"B \NAC \NWC"3;
"S \NAC"
BN"12"128;
%"TAP"
"6","(-3200,4350)","0","mstr_standard","I118";
;
HDL_TAP"TRUE"
BODY_TYPE"PLUMBING"
CDS_LIB"mstr_standard";
"B \NAC \NWC"3;
"S \NAC"
BN"11"120;
%"TAP"
"6","(-3200,4300)","0","mstr_standard","I119";
;
HDL_TAP"TRUE"
BODY_TYPE"PLUMBING"
CDS_LIB"mstr_standard";
"B \NAC \NWC"3;
"S \NAC"
BN"10"121;
%"PVTT_ABC"
"1","(-850,2700)","0","mstr_symbols","I12";
;
HDL_POWER"PVTT_ABC"
ROOM"DDR4_CH_A"
BODY_TYPE"PLUMBING"
CDS_LIB"mstr_symbols"
BOM_COST"MEM"
VOLTAGE"0.6V";
"G\NAC"13;
%"TAP"
"6","(-3200,4250)","0","mstr_standard","I120";
;
HDL_TAP"TRUE"
BODY_TYPE"PLUMBING"
CDS_LIB"mstr_standard";
"B \NAC \NWC"3;
"S \NAC"
BN"9"122;
%"TAP"
"6","(-3200,4200)","0","mstr_standard","I121";
;
HDL_TAP"TRUE"
BODY_TYPE"PLUMBING"
CDS_LIB"mstr_standard";
"B \NAC \NWC"3;
"S \NAC"
BN"8"123;
%"TAP"
"6","(-3200,4150)","0","mstr_standard","I122";
;
HDL_TAP"TRUE"
BODY_TYPE"PLUMBING"
CDS_LIB"mstr_standard";
"B \NAC \NWC"3;
"S \NAC"
BN"7"124;
%"TAP"
"6","(-3200,4100)","0","mstr_standard","I123";
;
HDL_TAP"TRUE"
BODY_TYPE"PLUMBING"
CDS_LIB"mstr_standard";
"B \NAC \NWC"3;
"S \NAC"
BN"6"125;
%"TAP"
"6","(-3200,4050)","0","mstr_standard","I124";
;
HDL_TAP"TRUE"
BODY_TYPE"PLUMBING"
CDS_LIB"mstr_standard";
"B \NAC \NWC"3;
"S \NAC"
BN"5"52;
%"TAP"
"6","(-3200,4000)","0","mstr_standard","I125";
;
HDL_TAP"TRUE"
BODY_TYPE"PLUMBING"
CDS_LIB"mstr_standard";
"B \NAC \NWC"3;
"S \NAC"
BN"4"53;
%"TAP"
"6","(-3200,3950)","0","mstr_standard","I126";
;
HDL_TAP"TRUE"
BODY_TYPE"PLUMBING"
CDS_LIB"mstr_standard";
"B \NAC \NWC"3;
"S \NAC"
BN"3"54;
%"TAP"
"6","(-3200,3900)","0","mstr_standard","I128";
;
HDL_TAP"TRUE"
BODY_TYPE"PLUMBING"
CDS_LIB"mstr_standard";
"B \NAC \NWC"3;
"S \NAC"
BN"2"40;
%"TAP"
"6","(-3200,3850)","0","mstr_standard","I129";
;
HDL_TAP"TRUE"
BODY_TYPE"PLUMBING"
CDS_LIB"mstr_standard";
"B \NAC \NWC"3;
"S \NAC"
BN"1"55;
%"PVDDQ_ABC"
"1","(-1150,2600)","0","mstr_symbols","I13";
;
HDL_POWER"PVDDQ_ABC"
ROOM"DDR4_CH_A"
BODY_TYPE"PLUMBING"
CDS_LIB"mstr_symbols"
BOM_COST"MEM"
VOLTAGE"1.2V";
"G\NAC"14;
%"TAP"
"6","(-3200,3800)","0","mstr_standard","I130";
;
HDL_TAP"TRUE"
BODY_TYPE"PLUMBING"
CDS_LIB"mstr_standard";
"B \NAC \NWC"3;
"S \NAC"
BN"0"56;
%"TAP"
"6","(-3200,3700)","0","mstr_standard","I131";
;
HDL_TAP"TRUE"
BODY_TYPE"PLUMBING"
CDS_LIB"mstr_standard";
"B \NAC \NWC"11;
"S \NAC"
BN"1"60;
%"TAP"
"6","(-3200,3650)","0","mstr_standard","I132";
;
HDL_TAP"TRUE"
BODY_TYPE"PLUMBING"
CDS_LIB"mstr_standard";
"B \NAC \NWC"11;
"S \NAC"
BN"0"41;
%"TAP"
"6","(-3200,3550)","0","mstr_standard","I133";
;
HDL_TAP"TRUE"
BODY_TYPE"PLUMBING"
CDS_LIB"mstr_standard";
"B \NAC \NWC"10;
"S \NAC"
BN"0"43;
%"TAP"
"6","(-3200,3600)","0","mstr_standard","I134";
;
HDL_TAP"TRUE"
BODY_TYPE"PLUMBING"
CDS_LIB"mstr_standard";
"B \NAC \NWC"10;
"S \NAC"
BN"1"42;
%"TAP"
"6","(-3200,2600)","0","mstr_standard","I138";
;
HDL_TAP"TRUE"
BODY_TYPE"PLUMBING"
CDS_LIB"mstr_standard";
"B \NAC \NWC"8;
"S \NAC"
BN"6"39;
%"TAP"
"6","(-3200,2550)","0","mstr_standard","I139";
;
HDL_TAP"TRUE"
BODY_TYPE"PLUMBING"
CDS_LIB"mstr_standard";
"B \NAC \NWC"8;
"S \NAC"
BN"7"51;
%"TAP"
"6","(900,4650)","2","mstr_standard","I14";
;
HDL_TAP"TRUE"
BODY_TYPE"PLUMBING"
CDS_LIB"mstr_standard";
"B \NAC \NWC"2;
"S \NAC"
BN"12"170;
%"TAP"
"6","(-3200,2500)","0","mstr_standard","I140";
;
HDL_TAP"TRUE"
BODY_TYPE"PLUMBING"
CDS_LIB"mstr_standard";
"B \NAC \NWC"8;
"S \NAC"
BN"4"50;
%"TAP"
"6","(-3200,2450)","0","mstr_standard","I141";
;
HDL_TAP"TRUE"
BODY_TYPE"PLUMBING"
CDS_LIB"mstr_standard";
"B \NAC \NWC"8;
"S \NAC"
BN"5"49;
%"TAP"
"6","(-3200,2400)","0","mstr_standard","I142";
;
HDL_TAP"TRUE"
BODY_TYPE"PLUMBING"
CDS_LIB"mstr_standard";
"B \NAC \NWC"8;
"S \NAC"
BN"2"48;
%"TAP"
"6","(-3200,2350)","0","mstr_standard","I143";
;
HDL_TAP"TRUE"
BODY_TYPE"PLUMBING"
CDS_LIB"mstr_standard";
"B \NAC \NWC"8;
"S \NAC"
BN"3"47;
%"TAP"
"6","(-3200,2300)","0","mstr_standard","I144";
;
HDL_TAP"TRUE"
BODY_TYPE"PLUMBING"
CDS_LIB"mstr_standard";
"B \NAC \NWC"8;
"S \NAC"
BN"0"46;
%"TAP"
"6","(-3200,2250)","0","mstr_standard","I145";
;
HDL_TAP"TRUE"
BODY_TYPE"PLUMBING"
CDS_LIB"mstr_standard";
"B \NAC \NWC"8;
"S \NAC"
BN"1"45;
%"TAP"
"6","(900,4750)","2","mstr_standard","I15";
;
HDL_TAP"TRUE"
BODY_TYPE"PLUMBING"
CDS_LIB"mstr_standard";
"B \NAC \NWC"2;
"S \NAC"
BN"13"168;
%"TAP"
"6","(-3200,2700)","0","mstr_standard","I152";
;
HDL_TAP"TRUE"
BODY_TYPE"PLUMBING"
CDS_LIB"mstr_standard";
"B \NAC \NWC"12;
"S \NAC"
BN"0"38;
%"TAP"
"6","(-3200,2750)","0","mstr_standard","I153";
;
HDL_TAP"TRUE"
BODY_TYPE"PLUMBING"
CDS_LIB"mstr_standard";
"B \NAC \NWC"12;
"S \NAC"
BN"1"37;
%"TAP"
"6","(-3200,2900)","0","mstr_standard","I155";
;
HDL_TAP"TRUE"
BODY_TYPE"PLUMBING"
CDS_LIB"mstr_standard";
"B \NAC \NWC"9;
"S \NAC"
BN"1"44;
%"TAP"
"6","(-3200,2850)","0","mstr_standard","I156";
;
HDL_TAP"TRUE"
BODY_TYPE"PLUMBING"
CDS_LIB"mstr_standard";
"B \NAC \NWC"9;
"S \NAC"
BN"0"36;
%"TAP"
"6","(-3200,3150)","0","mstr_standard","I158";
;
HDL_TAP"TRUE"
BODY_TYPE"PLUMBING"
CDS_LIB"mstr_standard";
"B \NAC \NWC"7;
"S \NAC"
BN"3"59;
%"TAP"
"6","(700,4800)","2","mstr_standard","I16";
;
HDL_TAP"TRUE"
BODY_TYPE"PLUMBING"
CDS_LIB"mstr_standard";
"B \NAC \NWC"1;
"S \NAC"
BN"13"167;
%"TAP"
"6","(-3200,3100)","0","mstr_standard","I160";
;
HDL_TAP"TRUE"
BODY_TYPE"PLUMBING"
CDS_LIB"mstr_standard";
"B \NAC \NWC"7;
"S \NAC"
BN"2"58;
%"TAP"
"6","(-3200,3050)","0","mstr_standard","I161";
;
HDL_TAP"TRUE"
BODY_TYPE"PLUMBING"
CDS_LIB"mstr_standard";
"B \NAC \NWC"7;
"S \NAC"
BN"1"57;
%"TAP"
"6","(-3200,3000)","0","mstr_standard","I162";
;
HDL_TAP"TRUE"
BODY_TYPE"PLUMBING"
CDS_LIB"mstr_standard";
"B \NAC \NWC"7;
"S \NAC"
BN"0"35;
%"TAP"
"6","(700,4700)","2","mstr_standard","I17";
;
HDL_TAP"TRUE"
BODY_TYPE"PLUMBING"
CDS_LIB"mstr_standard";
"B \NAC \NWC"1;
"S \NAC"
BN"12"169;
%"TAP"
"6","(-3750,3300)","0","mstr_standard","I174";
;
HDL_TAP"TRUE"
BODY_TYPE"PLUMBING"
CDS_LIB"mstr_standard";
"B \NAC \NWC"5;
"S \NAC"
BN"0"62;
%"TAP"
"6","(-3600,3350)","0","mstr_standard","I175";
;
HDL_TAP"TRUE"
BODY_TYPE"PLUMBING"
CDS_LIB"mstr_standard";
"B \NAC \NWC"6;
"S \NAC"
BN"0"63;
%"SCONN288_H44441004"
"4","(0,2050)","0","mstr_sconn","I179";
;
CDS_SEC"4"
ROOM"DDR4_CH_C"
CDS_LOCATION"J4G3"
SEC"4"
SEC_TYPE"PIP"
CDS_LIB"mstr_sconn"
BOM_COST"MEM"
PACK_TYPE"PIP"
MATERIAL"SCONN"
PART_NUMBER"H44441-004"
LOCATION"J4G3";
"VPP<4>"
$PN"142"18;
"VTT<1>"
$PN"77"13;
"VPP<0>"
$PN"287"18;
"VPP<1>"
$PN"286"18;
"VPP<2>"
$PN"288"18;
"VPP<3>"
$PN"143"18;
"VDD<1>"
$PN"233"14;
"VDD<2>"
$PN"231"14;
"VDD<3>"
$PN"229"14;
"VDD<4>"
$PN"226"14;
"VDD<5>"
$PN"223"14;
"VDD<7>"
$PN"217"14;
"VDD<8>"
$PN"215"14;
"VDD<9>"
$PN"212"14;
"VDD<11>"
$PN"206"14;
"VDD<12>"
$PN"204"14;
"VDD<14>"
$PN"90"14;
"VDD<15>"
$PN"88"14;
"VDD<17>"
$PN"83"14;
"VDD<18>"
$PN"80"14;
"VDD<20>"
$PN"73"14;
"VDD<21>"
$PN"70"14;
"VDD<22>"
$PN"67"14;
"VDD<24>"
$PN"61"14;
"12V<0>"
$PN"145"20;
"12V<1>"
$PN"1"20;
"VTT<0>"
$PN"221"13;
"VDD<25>"
$PN"59"14;
"VDD<23>"
$PN"64"14;
"VDD<19>"
$PN"76"14;
"VDD<16>"
$PN"85"14;
"VDD<13>"
$PN"92"14;
"VDD<10>"
$PN"209"14;
"VDD<6>"
$PN"220"14;
"VDD<0>"
$PN"236"14;
%"TAP"
"6","(700,4600)","2","mstr_standard","I18";
;
HDL_TAP"TRUE"
BODY_TYPE"PLUMBING"
CDS_LIB"mstr_standard";
"B \NAC \NWC"1;
"S \NAC"
BN"11"171;
%"GND"
"1","(2500,1350)","2","mstr_symbols","I180";
;
HDL_POWER"GND"
ROOM"DDR4_CH_A"
BODY_TYPE"PLUMBING"
BOM_COST"MEM"
CDS_LIB"mstr_symbols"
SIZE"1B"
VOLTAGE"0";
"A\NAC"15;
%"GND"
"1","(-4950,1650)","2","mstr_symbols","I184";
;
HDL_POWER"GND"
ROOM"DDR4_CH_A"
BODY_TYPE"PLUMBING"
SIZE"1B"
CDS_LIB"mstr_symbols"
BOM_COST"MEM"
VOLTAGE"0";
"A\NAC"16;
%"CAP_A"
"1","(-4650,1300)","2","dev_discrete","I188";
;
ROOM"DDR4_CH_C"
SEC"1"
SEC_TYPE"0402V"
CDS_SEC"1"
CDS_LIB"dev_discrete"
BOM_COST"MEM"
CDS_LOCATION"C4G19"
MATERIAL"X7R"
VOLTAGE"25V"
PACK_TYPE"0402V"
TOLERANCE"10%"
VALUE"0.01UF"
PART_NUMBER"A36096-045"
LOCATION"C4G19";
"B"
$PN"2"17;
"A"
$PN"1"22;
%"GND"
"1","(-4650,1050)","0","mstr_symbols","I189";
;
HDL_POWER"GND"
ROOM"DDR4_CH_A"
BODY_TYPE"PLUMBING"
SIZE"1B"
CDS_LIB"mstr_symbols"
BOM_COST"MEM"
VOLTAGE"0";
"A\NAC"17;
%"TAP"
"6","(900,4450)","2","mstr_standard","I19";
;
HDL_TAP"TRUE"
BODY_TYPE"PLUMBING"
CDS_LIB"mstr_standard";
"B \NAC \NWC"2;
"S \NAC"
BN"10"174;
%"PVPP_ABC"
"1","(-700,3050)","0","mstr_symbols","I190";
;
HDL_POWER"PVPP_ABC"
ROOM"DDR4_CH_A"
BODY_TYPE"PLUMBING"
CDS_LIB"mstr_symbols"
BOM_COST"MEM"
VOLTAGE"2.5V";
"G\NAC"18;
%"PVPP_ABC"
"1","(-4950,2000)","0","mstr_symbols","I191";
;
HDL_POWER"PVPP_ABC"
ROOM"DDR4_CH_A"
BODY_TYPE"PLUMBING"
CDS_LIB"mstr_symbols"
BOM_COST"MEM"
VOLTAGE"2.5V";
"G\NAC"19;
%"TAP"
"6","(-3600,3450)","0","mstr_standard","I196";
;
HDL_TAP"TRUE"
BODY_TYPE"PLUMBING"
CDS_LIB"mstr_standard";
"B \NAC \NWC"6;
"S \NAC"
BN"1"61;
%"TAP"
"6","(-3750,3400)","0","mstr_standard","I197";
;
HDL_TAP"TRUE"
BODY_TYPE"PLUMBING"
CDS_LIB"mstr_standard";
"B \NAC \NWC"5;
"S \NAC"
BN"1"64;
%"P12V_NVDIMM_ABC"
"1","(700,3125)","0","mstr_symbols","I198";
;
HDL_POWER"P12V_NVDIMM_ABC"
BODY_TYPE"PLUMBING"
CDS_LIB"mstr_symbols"
VOLTAGE"12.0";
"G\NAC"20;
%"TAP"
"6","(900,4550)","2","mstr_standard","I20";
;
HDL_TAP"TRUE"
BODY_TYPE"PLUMBING"
CDS_LIB"mstr_standard";
"B \NAC \NWC"2;
"S \NAC"
BN"11"172;
%"TAP"
"6","(900,4350)","2","mstr_standard","I21";
;
HDL_TAP"TRUE"
BODY_TYPE"PLUMBING"
CDS_LIB"mstr_standard";
"B \NAC \NWC"2;
"S \NAC"
BN"9"155;
%"TAP"
"6","(700,4500)","2","mstr_standard","I22";
;
HDL_TAP"TRUE"
BODY_TYPE"PLUMBING"
CDS_LIB"mstr_standard";
"B \NAC \NWC"1;
"S \NAC"
BN"10"173;
%"TAP"
"6","(700,4400)","2","mstr_standard","I23";
;
HDL_TAP"TRUE"
BODY_TYPE"PLUMBING"
CDS_LIB"mstr_standard";
"B \NAC \NWC"1;
"S \NAC"
BN"9"154;
%"TAP"
"6","(900,4150)","2","mstr_standard","I24";
;
HDL_TAP"TRUE"
BODY_TYPE"PLUMBING"
CDS_LIB"mstr_standard";
"B \NAC \NWC"2;
"S \NAC"
BN"7"159;
%"TAP"
"6","(900,4250)","2","mstr_standard","I25";
;
HDL_TAP"TRUE"
BODY_TYPE"PLUMBING"
CDS_LIB"mstr_standard";
"B \NAC \NWC"2;
"S \NAC"
BN"8"157;
%"TAP"
"6","(700,4300)","2","mstr_standard","I26";
;
HDL_TAP"TRUE"
BODY_TYPE"PLUMBING"
CDS_LIB"mstr_standard";
"B \NAC \NWC"1;
"S \NAC"
BN"8"156;
%"TAP"
"6","(700,4200)","2","mstr_standard","I27";
;
HDL_TAP"TRUE"
BODY_TYPE"PLUMBING"
CDS_LIB"mstr_standard";
"B \NAC \NWC"1;
"S \NAC"
BN"7"158;
%"TAP"
"6","(700,4100)","2","mstr_standard","I28";
;
HDL_TAP"TRUE"
BODY_TYPE"PLUMBING"
CDS_LIB"mstr_standard";
"B \NAC \NWC"1;
"S \NAC"
BN"6"160;
%"TAP"
"6","(900,3950)","2","mstr_standard","I29";
;
HDL_TAP"TRUE"
BODY_TYPE"PLUMBING"
CDS_LIB"mstr_standard";
"B \NAC \NWC"2;
"S \NAC"
BN"5"143;
%"TAP"
"6","(900,5150)","2","mstr_standard","I3";
;
HDL_TAP"TRUE"
BODY_TYPE"PLUMBING"
CDS_LIB"mstr_standard";
"B \NAC \NWC"2;
"S \NAC"
BN"17"176;
%"TAP"
"6","(900,4050)","2","mstr_standard","I30";
;
HDL_TAP"TRUE"
BODY_TYPE"PLUMBING"
CDS_LIB"mstr_standard";
"B \NAC \NWC"2;
"S \NAC"
BN"6"141;
%"TAP"
"6","(900,3850)","2","mstr_standard","I31";
;
HDL_TAP"TRUE"
BODY_TYPE"PLUMBING"
CDS_LIB"mstr_standard";
"B \NAC \NWC"2;
"S \NAC"
BN"4"145;
%"TAP"
"6","(700,4000)","2","mstr_standard","I32";
;
HDL_TAP"TRUE"
BODY_TYPE"PLUMBING"
CDS_LIB"mstr_standard";
"B \NAC \NWC"1;
"S \NAC"
BN"5"142;
%"TAP"
"6","(700,3900)","2","mstr_standard","I33";
;
HDL_TAP"TRUE"
BODY_TYPE"PLUMBING"
CDS_LIB"mstr_standard";
"B \NAC \NWC"1;
"S \NAC"
BN"4"144;
%"TAP"
"6","(700,3800)","2","mstr_standard","I34";
;
HDL_TAP"TRUE"
BODY_TYPE"PLUMBING"
CDS_LIB"mstr_standard";
"B \NAC \NWC"1;
"S \NAC"
BN"3"146;
%"TAP"
"6","(900,3550)","2","mstr_standard","I35";
;
HDL_TAP"TRUE"
BODY_TYPE"PLUMBING"
CDS_LIB"mstr_standard";
"B \NAC \NWC"2;
"S \NAC"
BN"1"151;
%"TAP"
"6","(900,3650)","2","mstr_standard","I36";
;
HDL_TAP"TRUE"
BODY_TYPE"PLUMBING"
CDS_LIB"mstr_standard";
"B \NAC \NWC"2;
"S \NAC"
BN"2"149;
%"TAP"
"6","(900,3750)","2","mstr_standard","I37";
;
HDL_TAP"TRUE"
BODY_TYPE"PLUMBING"
CDS_LIB"mstr_standard";
"B \NAC \NWC"2;
"S \NAC"
BN"3"147;
%"TAP"
"6","(700,3700)","2","mstr_standard","I38";
;
HDL_TAP"TRUE"
BODY_TYPE"PLUMBING"
CDS_LIB"mstr_standard";
"B \NAC \NWC"1;
"S \NAC"
BN"2"148;
%"TAP"
"6","(700,3600)","2","mstr_standard","I39";
;
HDL_TAP"TRUE"
BODY_TYPE"PLUMBING"
CDS_LIB"mstr_standard";
"B \NAC \NWC"1;
"S \NAC"
BN"1"150;
%"TAP"
"6","(700,5200)","2","mstr_standard","I4";
;
HDL_TAP"TRUE"
BODY_TYPE"PLUMBING"
CDS_LIB"mstr_standard";
"B \NAC \NWC"1;
"S \NAC"
BN"17"175;
%"TAP"
"6","(900,3450)","2","mstr_standard","I40";
;
HDL_TAP"TRUE"
BODY_TYPE"PLUMBING"
CDS_LIB"mstr_standard";
"B \NAC \NWC"2;
"S \NAC"
BN"0"153;
%"TAP"
"6","(700,3500)","2","mstr_standard","I41";
;
HDL_TAP"TRUE"
BODY_TYPE"PLUMBING"
CDS_LIB"mstr_standard";
"B \NAC \NWC"1;
"S \NAC"
BN"0"152;
%"SCONN288_H44441004"
"3","(1800,2650)","0","mstr_sconn","I43";
;
CDS_SEC"3"
ROOM"DDR4_CH_C"
CDS_LOCATION"J4G3"
SEC"3"
SEC_TYPE"PIP"
CDS_LIB"mstr_sconn"
BOM_COST"MEM"
PACK_TYPE"PIP"
MATERIAL"SCONN"
PART_NUMBER"H44441-004"
LOCATION"J4G3";
"VSS<93>"
$PN"2"21;
"VSS<92>"
$PN"4"21;
"VSS<91>"
$PN"6"21;
"VSS<90>"
$PN"9"21;
"VSS<89>"
$PN"11"21;
"VSS<88>"
$PN"13"21;
"VSS<0>"
$PN"283"15;
"VSS<1>"
$PN"281"15;
"VSS<2>"
$PN"279"15;
"VSS<3>"
$PN"276"15;
"VSS<4>"
$PN"274"15;
"VSS<5>"
$PN"272"15;
"VSS<6>"
$PN"270"15;
"VSS<7>"
$PN"268"15;
"VSS<8>"
$PN"265"15;
"VSS<9>"
$PN"263"15;
"VSS<10>"
$PN"261"15;
"VSS<11>"
$PN"259"15;
"VSS<12>"
$PN"257"15;
"VSS<13>"
$PN"254"15;
"VSS<14>"
$PN"252"15;
"VSS<15>"
$PN"250"15;
"VSS<16>"
$PN"248"15;
"VSS<17>"
$PN"246"15;
"VSS<18>"
$PN"243"15;
"VSS<19>"
$PN"241"15;
"VSS<20>"
$PN"239"15;
"VSS<21>"
$PN"202"15;
"VSS<22>"
$PN"200"15;
"VSS<23>"
$PN"198"15;
"VSS<24>"
$PN"195"15;
"VSS<25>"
$PN"193"15;
"VSS<26>"
$PN"191"15;
"VSS<27>"
$PN"189"15;
"VSS<28>"
$PN"187"15;
"VSS<29>"
$PN"184"15;
"VSS<30>"
$PN"182"15;
"VSS<31>"
$PN"180"15;
"VSS<32>"
$PN"178"15;
"VSS<33>"
$PN"176"15;
"VSS<34>"
$PN"173"15;
"VSS<35>"
$PN"171"15;
"VSS<36>"
$PN"169"15;
"VSS<37>"
$PN"167"15;
"VSS<38>"
$PN"165"15;
"VSS<39>"
$PN"162"15;
"VSS<40>"
$PN"160"15;
"VSS<41>"
$PN"158"15;
"VSS<42>"
$PN"156"15;
"VSS<43>"
$PN"154"15;
"VSS<44>"
$PN"151"15;
"VSS<47>"
$PN"138"21;
"VSS<48>"
$PN"136"21;
"VSS<49>"
$PN"134"21;
"VSS<50>"
$PN"131"21;
"VSS<51>"
$PN"129"21;
"VSS<52>"
$PN"127"21;
"VSS<53>"
$PN"125"21;
"VSS<54>"
$PN"123"21;
"VSS<55>"
$PN"120"21;
"VSS<56>"
$PN"118"21;
"VSS<57>"
$PN"116"21;
"VSS<58>"
$PN"114"21;
"VSS<59>"
$PN"112"21;
"VSS<60>"
$PN"109"21;
"VSS<61>"
$PN"107"21;
"VSS<62>"
$PN"105"21;
"VSS<63>"
$PN"103"21;
"VSS<64>"
$PN"101"21;
"VSS<65>"
$PN"98"21;
"VSS<66>"
$PN"96"21;
"VSS<67>"
$PN"94"21;
"VSS<68>"
$PN"57"21;
"VSS<69>"
$PN"55"21;
"VSS<70>"
$PN"53"21;
"VSS<71>"
$PN"50"21;
"VSS<72>"
$PN"48"21;
"VSS<73>"
$PN"46"21;
"VSS<74>"
$PN"44"21;
"VSS<75>"
$PN"42"21;
"VSS<76>"
$PN"39"21;
"VSS<77>"
$PN"37"21;
"VSS<78>"
$PN"35"21;
"VSS<79>"
$PN"33"21;
"VSS<80>"
$PN"31"21;
"VSS<81>"
$PN"28"21;
"VSS<82>"
$PN"26"21;
"VSS<83>"
$PN"24"21;
"VSS<84>"
$PN"22"21;
"VSS<85>"
$PN"20"21;
"VSS<86>"
$PN"17"21;
"VSS<87>"
$PN"15"21;
"VSS<45>"
$PN"149"15;
"VSS<46>"
$PN"147"15;
%"GND"
"1","(1100,1350)","2","mstr_symbols","I44";
;
HDL_POWER"GND"
ROOM"DDR4_CH_A"
BODY_TYPE"PLUMBING"
BOM_COST"MEM"
SIZE"1B"
CDS_LIB"mstr_symbols"
VOLTAGE"0";
"A\NAC"21;
%"TAP"
"6","(-1700,4650)","2","mstr_standard","I46";
;
HDL_TAP"TRUE"
BODY_TYPE"PLUMBING"
CDS_LIB"mstr_standard";
"B \NAC \NWC"4;
"S \NAC"
BN"62"140;
%"TAP"
"6","(-1700,4600)","2","mstr_standard","I47";
;
HDL_TAP"TRUE"
BODY_TYPE"PLUMBING"
CDS_LIB"mstr_standard";
"B \NAC \NWC"4;
"S \NAC"
BN"63"129;
%"TAP"
"6","(-1700,4450)","2","mstr_standard","I48";
;
HDL_TAP"TRUE"
BODY_TYPE"PLUMBING"
CDS_LIB"mstr_standard";
"B \NAC \NWC"4;
"S \NAC"
BN"58"138;
%"TAP"
"6","(-1700,4500)","2","mstr_standard","I49";
;
HDL_TAP"TRUE"
BODY_TYPE"PLUMBING"
CDS_LIB"mstr_standard";
"B \NAC \NWC"4;
"S \NAC"
BN"61"139;
%"TAP"
"6","(700,5100)","2","mstr_standard","I5";
;
HDL_TAP"TRUE"
BODY_TYPE"PLUMBING"
CDS_LIB"mstr_standard";
"B \NAC \NWC"1;
"S \NAC"
BN"16"161;
%"TAP"
"6","(-1700,4550)","2","mstr_standard","I50";
;
HDL_TAP"TRUE"
BODY_TYPE"PLUMBING"
CDS_LIB"mstr_standard";
"B \NAC \NWC"4;
"S \NAC"
BN"60"130;
%"TAP"
"6","(-1700,4350)","2","mstr_standard","I51";
;
HDL_TAP"TRUE"
BODY_TYPE"PLUMBING"
CDS_LIB"mstr_standard";
"B \NAC \NWC"4;
"S \NAC"
BN"56"135;
%"TAP"
"6","(-1700,4400)","2","mstr_standard","I52";
;
HDL_TAP"TRUE"
BODY_TYPE"PLUMBING"
CDS_LIB"mstr_standard";
"B \NAC \NWC"4;
"S \NAC"
BN"59"134;
%"TAP"
"6","(-1700,4200)","2","mstr_standard","I53";
;
HDL_TAP"TRUE"
BODY_TYPE"PLUMBING"
CDS_LIB"mstr_standard";
"B \NAC \NWC"4;
"S \NAC"
BN"55"133;
%"TAP"
"6","(-1700,4250)","2","mstr_standard","I54";
;
HDL_TAP"TRUE"
BODY_TYPE"PLUMBING"
CDS_LIB"mstr_standard";
"B \NAC \NWC"4;
"S \NAC"
BN"54"136;
%"TAP"
"6","(-1700,4300)","2","mstr_standard","I55";
;
HDL_TAP"TRUE"
BODY_TYPE"PLUMBING"
CDS_LIB"mstr_standard";
"B \NAC \NWC"4;
"S \NAC"
BN"57"137;
%"TAP"
"6","(-1700,4100)","2","mstr_standard","I56";
;
HDL_TAP"TRUE"
BODY_TYPE"PLUMBING"
CDS_LIB"mstr_standard";
"B \NAC \NWC"4;
"S \NAC"
BN"53"131;
%"TAP"
"6","(-1700,4150)","2","mstr_standard","I57";
;
HDL_TAP"TRUE"
BODY_TYPE"PLUMBING"
CDS_LIB"mstr_standard";
"B \NAC \NWC"4;
"S \NAC"
BN"52"132;
%"TAP"
"6","(-1700,4050)","2","mstr_standard","I58";
;
HDL_TAP"TRUE"
BODY_TYPE"PLUMBING"
CDS_LIB"mstr_standard";
"B \NAC \NWC"4;
"S \NAC"
BN"50"111;
%"TAP"
"6","(-1700,4000)","2","mstr_standard","I59";
;
HDL_TAP"TRUE"
BODY_TYPE"PLUMBING"
CDS_LIB"mstr_standard";
"B \NAC \NWC"4;
"S \NAC"
BN"51"110;
%"TAP"
"6","(900,4950)","2","mstr_standard","I6";
;
HDL_TAP"TRUE"
BODY_TYPE"PLUMBING"
CDS_LIB"mstr_standard";
"B \NAC \NWC"2;
"S \NAC"
BN"15"164;
%"TAP"
"6","(-1700,3950)","2","mstr_standard","I60";
;
HDL_TAP"TRUE"
BODY_TYPE"PLUMBING"
CDS_LIB"mstr_standard";
"B \NAC \NWC"4;
"S \NAC"
BN"48"109;
%"SCONN288_H44441004"
"2","(0,4350)","0","mstr_sconn","I61";
;
CDS_SEC"2"
ROOM"DDR4_CH_C"
CDS_LOCATION"J4G3"
SEC"2"
SEC_TYPE"PIP"
CDS_LIB"mstr_sconn"
BOM_COST"MEM"
PACK_TYPE"PIP"
MATERIAL"SCONN"
PART_NUMBER"H44441-004"
LOCATION"J4G3";
"DQS17P"
$PN"51"175;
"DQS9P"
$PN"7"154;
"DQS9N"
$PN"8"155;
"DQS8P"
$PN"197"156;
"DQS8N"
$PN"196"157;
"DQS7P"
$PN"278"158;
"DQS7N"
$PN"277"159;
"DQS6P"
$PN"267"160;
"DQS6N"
$PN"266"141;
"DQS5P"
$PN"256"142;
"DQS5N"
$PN"255"143;
"DQS4P"
$PN"245"144;
"DQS4N"
$PN"244"145;
"DQS3P"
$PN"186"146;
"DQS3N"
$PN"185"147;
"DQS2P"
$PN"175"148;
"DQS2N"
$PN"174"149;
"DQS1P"
$PN"164"150;
"DQS1N"
$PN"163"151;
"DQS17N"
$PN"52"176;
"DQS16P"
$PN"132"161;
"DQS16N"
$PN"133"162;
"DQS15P"
$PN"121"163;
"DQS15N"
$PN"122"164;
"DQS14P"
$PN"110"165;
"DQS14N"
$PN"111"166;
"DQS13P"
$PN"99"167;
"DQS13N"
$PN"100"168;
"DQS12P"
$PN"40"169;
"DQS12N"
$PN"41"170;
"DQS11P"
$PN"29"171;
"DQS11N"
$PN"30"172;
"DQS10P"
$PN"18"173;
"DQS10N"
$PN"19"174;
"DQS0P"
$PN"153"152;
"DQS0N"
$PN"152"153;
%"TAP"
"6","(-1700,3800)","2","mstr_standard","I62";
;
HDL_TAP"TRUE"
BODY_TYPE"PLUMBING"
CDS_LIB"mstr_standard";
"B \NAC \NWC"4;
"S \NAC"
BN"47"116;
%"TAP"
"6","(-1700,3850)","2","mstr_standard","I63";
;
HDL_TAP"TRUE"
BODY_TYPE"PLUMBING"
CDS_LIB"mstr_standard";
"B \NAC \NWC"4;
"S \NAC"
BN"46"107;
%"TAP"
"6","(-1700,3900)","2","mstr_standard","I64";
;
HDL_TAP"TRUE"
BODY_TYPE"PLUMBING"
CDS_LIB"mstr_standard";
"B \NAC \NWC"4;
"S \NAC"
BN"49"108;
%"TAP"
"6","(-1700,3750)","2","mstr_standard","I65";
;
HDL_TAP"TRUE"
BODY_TYPE"PLUMBING"
CDS_LIB"mstr_standard";
"B \NAC \NWC"4;
"S \NAC"
BN"44"115;
%"TAP"
"6","(-1700,3700)","2","mstr_standard","I66";
;
HDL_TAP"TRUE"
BODY_TYPE"PLUMBING"
CDS_LIB"mstr_standard";
"B \NAC \NWC"4;
"S \NAC"
BN"45"114;
%"TAP"
"6","(-1700,3650)","2","mstr_standard","I67";
;
HDL_TAP"TRUE"
BODY_TYPE"PLUMBING"
CDS_LIB"mstr_standard";
"B \NAC \NWC"4;
"S \NAC"
BN"42"113;
%"TAP"
"6","(-1700,3600)","2","mstr_standard","I68";
;
HDL_TAP"TRUE"
BODY_TYPE"PLUMBING"
CDS_LIB"mstr_standard";
"B \NAC \NWC"4;
"S \NAC"
BN"43"112;
%"TAP"
"6","(-1700,3550)","2","mstr_standard","I69";
;
HDL_TAP"TRUE"
BODY_TYPE"PLUMBING"
CDS_LIB"mstr_standard";
"B \NAC \NWC"4;
"S \NAC"
BN"40"106;
%"TAP"
"6","(900,5050)","2","mstr_standard","I7";
;
HDL_TAP"TRUE"
BODY_TYPE"PLUMBING"
CDS_LIB"mstr_standard";
"B \NAC \NWC"2;
"S \NAC"
BN"16"162;
%"TAP"
"6","(-1700,3450)","2","mstr_standard","I70";
;
HDL_TAP"TRUE"
BODY_TYPE"PLUMBING"
CDS_LIB"mstr_standard";
"B \NAC \NWC"4;
"S \NAC"
BN"38"104;
%"TAP"
"6","(-1700,3500)","2","mstr_standard","I71";
;
HDL_TAP"TRUE"
BODY_TYPE"PLUMBING"
CDS_LIB"mstr_standard";
"B \NAC \NWC"4;
"S \NAC"
BN"41"105;
%"TAP"
"6","(-1700,3300)","2","mstr_standard","I72";
;
HDL_TAP"TRUE"
BODY_TYPE"PLUMBING"
CDS_LIB"mstr_standard";
"B \NAC \NWC"4;
"S \NAC"
BN"37"98;
%"TAP"
"6","(-1700,3350)","2","mstr_standard","I73";
;
HDL_TAP"TRUE"
BODY_TYPE"PLUMBING"
CDS_LIB"mstr_standard";
"B \NAC \NWC"4;
"S \NAC"
BN"36"103;
%"TAP"
"6","(-1700,3400)","2","mstr_standard","I74";
;
HDL_TAP"TRUE"
BODY_TYPE"PLUMBING"
CDS_LIB"mstr_standard";
"B \NAC \NWC"4;
"S \NAC"
BN"39"97;
%"TAP"
"6","(-1700,3200)","2","mstr_standard","I75";
;
HDL_TAP"TRUE"
BODY_TYPE"PLUMBING"
CDS_LIB"mstr_standard";
"B \NAC \NWC"4;
"S \NAC"
BN"35"102;
%"TAP"
"6","(-1700,3250)","2","mstr_standard","I76";
;
HDL_TAP"TRUE"
BODY_TYPE"PLUMBING"
CDS_LIB"mstr_standard";
"B \NAC \NWC"4;
"S \NAC"
BN"34"99;
%"TAP"
"6","(-1700,3150)","2","mstr_standard","I77";
;
HDL_TAP"TRUE"
BODY_TYPE"PLUMBING"
CDS_LIB"mstr_standard";
"B \NAC \NWC"4;
"S \NAC"
BN"32"101;
%"TAP"
"6","(-1700,3100)","2","mstr_standard","I78";
;
HDL_TAP"TRUE"
BODY_TYPE"PLUMBING"
CDS_LIB"mstr_standard";
"B \NAC \NWC"4;
"S \NAC"
BN"33"100;
%"TAP"
"6","(-1700,3050)","2","mstr_standard","I79";
;
HDL_TAP"TRUE"
BODY_TYPE"PLUMBING"
CDS_LIB"mstr_standard";
"B \NAC \NWC"4;
"S \NAC"
BN"30"94;
%"TAP"
"6","(900,4850)","2","mstr_standard","I8";
;
HDL_TAP"TRUE"
BODY_TYPE"PLUMBING"
CDS_LIB"mstr_standard";
"B \NAC \NWC"2;
"S \NAC"
BN"14"166;
%"TAP"
"6","(-1700,2900)","2","mstr_standard","I80";
;
HDL_TAP"TRUE"
BODY_TYPE"PLUMBING"
CDS_LIB"mstr_standard";
"B \NAC \NWC"4;
"S \NAC"
BN"29"95;
%"TAP"
"6","(-1700,2950)","2","mstr_standard","I81";
;
HDL_TAP"TRUE"
BODY_TYPE"PLUMBING"
CDS_LIB"mstr_standard";
"B \NAC \NWC"4;
"S \NAC"
BN"28"96;
%"TAP"
"6","(-1700,3000)","2","mstr_standard","I82";
;
HDL_TAP"TRUE"
BODY_TYPE"PLUMBING"
CDS_LIB"mstr_standard";
"B \NAC \NWC"4;
"S \NAC"
BN"31"93;
%"TAP"
"6","(-1700,2850)","2","mstr_standard","I83";
;
HDL_TAP"TRUE"
BODY_TYPE"PLUMBING"
CDS_LIB"mstr_standard";
"B \NAC \NWC"4;
"S \NAC"
BN"26"88;
%"TAP"
"6","(-1700,2800)","2","mstr_standard","I84";
;
HDL_TAP"TRUE"
BODY_TYPE"PLUMBING"
CDS_LIB"mstr_standard";
"B \NAC \NWC"4;
"S \NAC"
BN"27"87;
%"TAP"
"6","(-1700,2650)","2","mstr_standard","I85";
;
HDL_TAP"TRUE"
BODY_TYPE"PLUMBING"
CDS_LIB"mstr_standard";
"B \NAC \NWC"4;
"S \NAC"
BN"22"90;
%"TAP"
"6","(-1700,2750)","2","mstr_standard","I86";
;
HDL_TAP"TRUE"
BODY_TYPE"PLUMBING"
CDS_LIB"mstr_standard";
"B \NAC \NWC"4;
"S \NAC"
BN"24"92;
%"TAP"
"6","(-1700,2700)","2","mstr_standard","I87";
;
HDL_TAP"TRUE"
BODY_TYPE"PLUMBING"
CDS_LIB"mstr_standard";
"B \NAC \NWC"4;
"S \NAC"
BN"25"91;
%"TAP"
"6","(-1700,2550)","2","mstr_standard","I88";
;
HDL_TAP"TRUE"
BODY_TYPE"PLUMBING"
CDS_LIB"mstr_standard";
"B \NAC \NWC"4;
"S \NAC"
BN"20"86;
%"TAP"
"6","(-1700,2600)","2","mstr_standard","I89";
;
HDL_TAP"TRUE"
BODY_TYPE"PLUMBING"
CDS_LIB"mstr_standard";
"B \NAC \NWC"4;
"S \NAC"
BN"23"89;
%"TAP"
"6","(700,5000)","2","mstr_standard","I9";
;
HDL_TAP"TRUE"
BODY_TYPE"PLUMBING"
CDS_LIB"mstr_standard";
"B \NAC \NWC"1;
"S \NAC"
BN"15"163;
%"TAP"
"6","(-1700,2500)","2","mstr_standard","I90";
;
HDL_TAP"TRUE"
BODY_TYPE"PLUMBING"
CDS_LIB"mstr_standard";
"B \NAC \NWC"4;
"S \NAC"
BN"21"85;
%"TAP"
"6","(-1700,2450)","2","mstr_standard","I91";
;
HDL_TAP"TRUE"
BODY_TYPE"PLUMBING"
CDS_LIB"mstr_standard";
"B \NAC \NWC"4;
"S \NAC"
BN"18"84;
%"TAP"
"6","(-1700,2400)","2","mstr_standard","I92";
;
HDL_TAP"TRUE"
BODY_TYPE"PLUMBING"
CDS_LIB"mstr_standard";
"B \NAC \NWC"4;
"S \NAC"
BN"19"83;
%"TAP"
"6","(-1700,2300)","2","mstr_standard","I93";
;
HDL_TAP"TRUE"
BODY_TYPE"PLUMBING"
CDS_LIB"mstr_standard";
"B \NAC \NWC"4;
"S \NAC"
BN"17"82;
%"TAP"
"6","(-1700,2350)","2","mstr_standard","I94";
;
HDL_TAP"TRUE"
BODY_TYPE"PLUMBING"
CDS_LIB"mstr_standard";
"B \NAC \NWC"4;
"S \NAC"
BN"16"76;
%"TAP"
"6","(-1700,2150)","2","mstr_standard","I95";
;
HDL_TAP"TRUE"
BODY_TYPE"PLUMBING"
CDS_LIB"mstr_standard";
"B \NAC \NWC"4;
"S \NAC"
BN"12"80;
%"TAP"
"6","(-1700,2200)","2","mstr_standard","I96";
;
HDL_TAP"TRUE"
BODY_TYPE"PLUMBING"
CDS_LIB"mstr_standard";
"B \NAC \NWC"4;
"S \NAC"
BN"15"81;
%"TAP"
"6","(-1700,2250)","2","mstr_standard","I97";
;
HDL_TAP"TRUE"
BODY_TYPE"PLUMBING"
CDS_LIB"mstr_standard";
"B \NAC \NWC"4;
"S \NAC"
BN"14"77;
%"TAP"
"6","(-1700,2050)","2","mstr_standard","I98";
;
HDL_TAP"TRUE"
BODY_TYPE"PLUMBING"
CDS_LIB"mstr_standard";
"B \NAC \NWC"4;
"S \NAC"
BN"10"78;
%"TAP"
"6","(-1700,2100)","2","mstr_standard","I99";
;
HDL_TAP"TRUE"
BODY_TYPE"PLUMBING"
CDS_LIB"mstr_standard";
"B \NAC \NWC"4;
"S \NAC"
BN"13"79;
END.
